FILE_TYPE = CONNECTIVITY;
{Allegro Design Entry HDL 17.4-2019 S026 (4007227) 1/17/2022}
"PAGE_NUMBER" = 397;
0"NC";
END.
